# S9S_MB_2U (Grand Teton) — schematic netlist excerpt (pin names and nets, part order shuffled) for the footprints in the layout excerpt that follows; sources: Cadence DE-HDL packaged netlist, KiCad conversion of 03242023_DA0F0TMBIJ0_F0T_Motherboard_J_brd_V01_OCP.brd

C614  Q_CAP  1UF 25V 10% EMPTY  pkg C0402  page 130 : A = RST_PLD_CPU1_DRAM_AB_N ; B = GND
R1437  Q_RES  10K 1% CHIP  pkg 0402LF  page 220 : A = FM_PLD_HEARTBEAT_LVC3 ; B = P3V3_AUX

(kicad_pcb
	(version 20260206)
	(generator "pcbnew")
	(generator_version "10.0")
	(general
		(thickness 1.6)
		(legacy_teardrops no)
	)
	(paper "A4")
	(title_block
		(title "03242023_DA0F0TMBIJ0_F0T_Motherboard_J_brd_V01_OCP.brd")
		(comment 1 "Grand Teton / footprints 4554-4555 of 6105")
	)
	(layers
		(0 "F.Cu" signal "TOP")
		(4 "In1.Cu" signal "GND")
		(6 "In2.Cu" signal "IN1")
		(8 "In3.Cu" signal "GND1")
		(10 "In4.Cu" signal "IN2")
		(12 "In5.Cu" signal "GND2")
		(14 "In6.Cu" signal "IN3")
		(16 "In7.Cu" signal "GND3")
		(18 "In8.Cu" signal "VCC")
		(20 "In9.Cu" signal "VCC1")
		(22 "In10.Cu" signal "GND4")
		(24 "In11.Cu" signal "IN4")
		(26 "In12.Cu" signal "GND5")
		(28 "In13.Cu" signal "IN5")
		(30 "In14.Cu" signal "GND6")
		(32 "In15.Cu" signal "IN6")
		(34 "In16.Cu" signal "GND7")
		(2 "B.Cu" signal "BOTTOM")
		(9 "F.Adhes" user "F.Adhesive")
		(11 "B.Adhes" user "B.Adhesive")
		(13 "F.Paste" user "Package Geometry/Pastemask Top")
		(15 "B.Paste" user "Package Geometry/Pastemask Bottom")
		(5 "F.SilkS" user "Ref Des/Silkscreen Top")
		(7 "B.SilkS" user "Ref Des/Silkscreen Bottom")
		(1 "F.Mask" user "Board Geometry/Soldermask Top")
		(3 "B.Mask" user "Board Geometry/Soldermask Bottom")
		(17 "Dwgs.User" user "User.Drawings")
		(19 "Cmts.User" user "User.Comments")
		(21 "Eco1.User" user "User.Eco1")
		(23 "Eco2.User" user "User.Eco2")
		(25 "Edge.Cuts" user "Board Geometry/Outline")
		(27 "Margin" user)
		(31 "F.CrtYd" user "Package Geometry/Place Bound Top")
		(29 "B.CrtYd" user "Package Geometry/Place Bound Bottom")
		(35 "F.Fab" user "Ref Des/Assembly Top")
		(33 "B.Fab" user "Ref Des/Assembly Bottom")
	)
	(footprint ""
		(layer "B.Cu")
		(at 34.551366 -192.924176 -90)
		(property "Reference" "C614"
			(at 0 0 90)
			(layer "B.SilkS")
			(hide yes)
			(effects
				(font
					(size 1.27 1.27)
				)
				(justify mirror)
			)
		)
		(property "Value" ""
			(at 0 0 90)
			(layer "B.Fab")
			(effects
				(font
					(size 1.27 1.27)
				)
				(justify mirror)
			)
		)
		(duplicate_pad_numbers_are_jumpers no)
		(fp_line
			(start -0.7874 0.4064)
			(end 0.7874 0.4064)
			(stroke
				(width 0.1524)
				(type default)
			)
			(layer "B.SilkS")
		)
		(fp_line
			(start 0.7874 0.4064)
			(end 0.7874 -0.4064)
			(stroke
				(width 0.1524)
				(type default)
			)
			(layer "B.SilkS")
		)
		(fp_line
			(start -0.7874 -0.4064)
			(end -0.7874 0.4064)
			(stroke
				(width 0.1524)
				(type default)
			)
			(layer "B.SilkS")
		)
		(fp_line
			(start 0.7874 -0.4064)
			(end -0.7874 -0.4064)
			(stroke
				(width 0.1524)
				(type default)
			)
			(layer "B.SilkS")
		)
		(fp_line
			(start -0.67945 0.3048)
			(end -0.120396 0.3048)
			(stroke
				(width 0.1)
				(type default)
			)
			(layer "B.Fab")
		)
		(fp_line
			(start -0.120396 0.3048)
			(end -0.120396 0.2794)
			(stroke
				(width 0.1)
				(type default)
			)
			(layer "B.Fab")
		)
		(fp_line
			(start 0.12065 0.3048)
			(end 0.67945 0.3048)
			(stroke
				(width 0.1)
				(type default)
			)
			(layer "B.Fab")
		)
		(fp_line
			(start 0.67945 0.3048)
			(end 0.67945 -0.305054)
			(stroke
				(width 0.1)
				(type default)
			)
			(layer "B.Fab")
		)
		(fp_line
			(start -0.120396 0.2794)
			(end 0.12065 0.2794)
			(stroke
				(width 0.1)
				(type default)
			)
			(layer "B.Fab")
		)
		(fp_line
			(start 0.12065 0.2794)
			(end 0.12065 0.3048)
			(stroke
				(width 0.1)
				(type default)
			)
			(layer "B.Fab")
		)
		(fp_line
			(start -0.12065 -0.2794)
			(end -0.12065 -0.3048)
			(stroke
				(width 0.1)
				(type default)
			)
			(layer "B.Fab")
		)
		(fp_line
			(start 0.12065 -0.2794)
			(end -0.12065 -0.2794)
			(stroke
				(width 0.1)
				(type default)
			)
			(layer "B.Fab")
		)
		(fp_line
			(start -0.67945 -0.3048)
			(end -0.67945 0.3048)
			(stroke
				(width 0.1)
				(type default)
			)
			(layer "B.Fab")
		)
		(fp_line
			(start -0.12065 -0.3048)
			(end -0.67945 -0.3048)
			(stroke
				(width 0.1)
				(type default)
			)
			(layer "B.Fab")
		)
		(fp_line
			(start 0.12065 -0.305054)
			(end 0.12065 -0.2794)
			(stroke
				(width 0.1)
				(type default)
			)
			(layer "B.Fab")
		)
		(fp_line
			(start 0.67945 -0.305054)
			(end 0.12065 -0.305054)
			(stroke
				(width 0.1)
				(type default)
			)
			(layer "B.Fab")
		)
		(pad "1" smd circle
			(at 0.40005 0 90)
			(size 0 0)
			(layers "B.Cu" "B.Mask" "B.Paste")
			(net "RST_PLD_CPU1_DRAM_AB_N")
		)
		(pad "2" smd circle
			(at -0.40005 0 90)
			(size 0 0)
			(layers "B.Cu" "B.Mask" "B.Paste")
			(net "GND")
		)
	)
	(footprint ""
		(layer "B.Cu")
		(at 193.60388 -107.495848 180)
		(property "Reference" "R1437"
			(at 0 0 0)
			(layer "B.SilkS")
			(hide yes)
			(effects
				(font
					(size 1.27 1.27)
				)
				(justify mirror)
			)
		)
		(property "Value" ""
			(at 0 0 0)
			(layer "B.Fab")
			(effects
				(font
					(size 1.27 1.27)
				)
				(justify mirror)
			)
		)
		(duplicate_pad_numbers_are_jumpers no)
		(fp_line
			(start 0.7874 0.4064)
			(end 0.7874 -0.4064)
			(stroke
				(width 0.1524)
				(type default)
			)
			(layer "B.SilkS")
		)
		(fp_line
			(start 0.7874 -0.4064)
			(end -0.7874 -0.4064)
			(stroke
				(width 0.1524)
				(type default)
			)
			(layer "B.SilkS")
		)
		(fp_line
			(start -0.7874 0.4064)
			(end 0.7874 0.4064)
			(stroke
				(width 0.1524)
				(type default)
			)
			(layer "B.SilkS")
		)
		(fp_line
			(start -0.7874 -0.4064)
			(end -0.7874 0.4064)
			(stroke
				(width 0.1524)
				(type default)
			)
			(layer "B.SilkS")
		)
		(fp_line
			(start 0.67945 0.3048)
			(end 0.67945 -0.305054)
			(stroke
				(width 0.1)
				(type default)
			)
			(layer "B.Fab")
		)
		(fp_line
			(start 0.67945 -0.305054)
			(end 0.12065 -0.305054)
			(stroke
				(width 0.1)
				(type default)
			)
			(layer "B.Fab")
		)
		(fp_line
			(start 0.12065 0.3048)
			(end 0.67945 0.3048)
			(stroke
				(width 0.1)
				(type default)
			)
			(layer "B.Fab")
		)
		(fp_line
			(start 0.12065 0.2794)
			(end 0.12065 0.3048)
			(stroke
				(width 0.1)
				(type default)
			)
			(layer "B.Fab")
		)
		(fp_line
			(start 0.12065 -0.2794)
			(end -0.12065 -0.2794)
			(stroke
				(width 0.1)
				(type default)
			)
			(layer "B.Fab")
		)
		(fp_line
			(start 0.12065 -0.305054)
			(end 0.12065 -0.2794)
			(stroke
				(width 0.1)
				(type default)
			)
			(layer "B.Fab")
		)
		(fp_line
			(start -0.120396 0.3048)
			(end -0.120396 0.2794)
			(stroke
				(width 0.1)
				(type default)
			)
			(layer "B.Fab")
		)
		(fp_line
			(start -0.120396 0.2794)
			(end 0.12065 0.2794)
			(stroke
				(width 0.1)
				(type default)
			)
			(layer "B.Fab")
		)
		(fp_line
			(start -0.12065 -0.2794)
			(end -0.12065 -0.3048)
			(stroke
				(width 0.1)
				(type default)
			)
			(layer "B.Fab")
		)
		(fp_line
			(start -0.12065 -0.3048)
			(end -0.67945 -0.3048)
			(stroke
				(width 0.1)
				(type default)
			)
			(layer "B.Fab")
		)
		(fp_line
			(start -0.67945 0.3048)
			(end -0.120396 0.3048)
			(stroke
				(width 0.1)
				(type default)
			)
			(layer "B.Fab")
		)
		(fp_line
			(start -0.67945 -0.3048)
			(end -0.67945 0.3048)
			(stroke
				(width 0.1)
				(type default)
			)
			(layer "B.Fab")
		)
		(pad "1" smd circle
			(at 0.40005 0)
			(size 0 0)
			(layers "B.Cu" "B.Mask" "B.Paste")
			(net "FM_PLD_HEARTBEAT_LVC3")
		)
		(pad "2" smd circle
			(at -0.40005 0)
			(size 0 0)
			(layers "B.Cu" "B.Mask" "B.Paste")
			(net "P3V3_AUX")
		)
	)
)
